(kicad_pcb
	(version 20211014)
	(generator pcbnew)
	(general
    (thickness 1.6)
  )
	(paper "A4")
	(title_block
    (title "SA800U (Snapdragon 845) Baseboard")
    (date "2023-10-19")
    (rev "1.0.3")
    (company "Antmicro Ltd.")
    (comment 1 "www.antmicro.com")
		(comment 9 "footprints 261-268 of 589")
	)
	(layers
    (0 "F.Cu" signal)
    (1 "In1.Cu" power)
    (2 "In2.Cu" signal)
    (3 "In3.Cu" signal)
    (4 "In4.Cu" power)
    (31 "B.Cu" signal)
    (32 "B.Adhes" user "B.Adhesive")
    (33 "F.Adhes" user "F.Adhesive")
    (34 "B.Paste" user)
    (35 "F.Paste" user)
    (36 "B.SilkS" user "B.Silkscreen")
    (37 "F.SilkS" user "F.Silkscreen")
    (38 "B.Mask" user)
    (39 "F.Mask" user)
    (40 "Dwgs.User" user "User.Drawings")
    (41 "Cmts.User" user "User.Comments")
    (42 "Eco1.User" user "User.Eco1")
    (43 "Eco2.User" user "User.Eco2")
    (44 "Edge.Cuts" user)
    (45 "Margin" user)
    (46 "B.CrtYd" user "B.Courtyard")
    (47 "F.CrtYd" user "F.Courtyard")
    (48 "B.Fab" user)
    (49 "F.Fab" user)
  )
	(footprint "sa800u-baseboard-hw-footprints:SA800U-WF" (layer "F.Cu")
    (tedit 61E0073C)
    (at 83.5 82.5)
    (property "Author" "Antmicro")
    (property "License" "Apache-2.0")
    (property "MPN" "SA800U-WF")
    (property "Manufacturer" "Quectel")
    (property "Sheetfile" "som.kicad_sch")
    (property "Sheetname" "SoM")
    (attr exclude_from_pos_files)
    (fp_text reference "A1" (at 0 -1.8) (layer "F.Fab")
      (effects (font (size 0.7 0.7) (thickness 0.15)) (justify left bottom))
    )
    (fp_text value "SA800U-WF" (at 0 -0.7) (layer "F.Fab")
      (effects (font (size 0.7 0.7) (thickness 0.15)) (justify left bottom))
    )
    (fp_text user "${REFERENCE}" (at -0.001 38.999) (layer "F.Fab") hide
      (effects (font (size 0.7 0.7) (thickness 0.15)) (justify left bottom))
    )
    (fp_text user "License: Apache-2.0" (at -0.001 41.4) (layer "F.Fab") hide
      (effects (font (size 0.7 0.7) (thickness 0.15)) (justify left bottom))
    )
    (fp_text user "Author: Antmicro" (at -0.001 40.2) (layer "F.Fab") hide
      (effects (font (size 0.7 0.7) (thickness 0.15)) (justify left bottom))
    )
  )
	(footprint "sa800u-baseboard-hw-footprints:C_0805_2012Metric" (layer "B.Cu")
    (tedit 5FD9C126)
    (at 61.1 118.5 180)
    (descr "Capacitor SMD 0805")
    (tags "capacitor SMD 0805")
    (property "Author" "Antmicro")
    (property "Dielectric" "X7R")
    (property "License" "Apache-2.0")
    (property "MPN" "CL21B104KCFNNNE")
    (property "Manufacturer" "SAMSUNG")
    (property "Sheetfile" "poe.kicad_sch")
    (property "Sheetname" "PoE")
    (property "Val" "100n/100V")
    (property "Voltage" "100V")
    (attr smd)
    (fp_text reference "C144" (at -1.37 -1.77) (layer "B.SilkS")
      (effects (font (size 0.7 0.7) (thickness 0.15)) (justify left bottom mirror))
    )
    (fp_text value "C_100n_0805_100V" (at 0 -1.947) (layer "B.Fab")
      (effects (font (size 0.7 0.7) (thickness 0.15)) (justify left bottom mirror))
    )
    (fp_text user "Author: Antmicro" (at -1.9 -5.947) (layer "B.Fab") hide
      (effects (font (size 0.7 0.7) (thickness 0.15)) (justify left bottom mirror))
    )
    (fp_text user "License: Apache-2.0" (at -1.9 -4.947) (layer "B.Fab") hide
      (effects (font (size 0.7 0.7) (thickness 0.15)) (justify left bottom mirror))
    )
    (fp_text user "${REFERENCE}" (at -1.9 -3.947) (layer "B.Fab") hide
      (effects (font (size 0.7 0.7) (thickness 0.15)) (justify left bottom mirror))
    )
    (fp_line (start -0.3 0.8) (end 0.3 0.8) (layer "B.SilkS") (width 0.15))
    (fp_line (start -0.3 -0.8) (end 0.3 -0.8) (layer "B.SilkS") (width 0.15))
    (fp_rect (start -1.9 0.93) (end 1.9 -0.93) (layer "B.CrtYd") (width 0.05) (fill none))
    (fp_rect (start -0.95 0.675) (end 0.95 -0.675) (layer "B.Fab") (width 0.15) (fill none))
    (pad "1" smd rect (at -1.05 0 180) (size 1.2 1.2) (layers "B.Cu" "B.Paste" "B.Mask")
      (net 73 "/PoE/VDD_POE") (pintype "passive"))
    (pad "2" smd rect (at 1.05 0 180) (size 1.2 1.2) (layers "B.Cu" "B.Paste" "B.Mask")
      (net 135 "/PoE/VSS_POE") (pintype "passive"))
  )
	(footprint "sa800u-baseboard-hw-footprints:C_0805_2012Metric" (layer "B.Cu")
    (tedit 5FD9C126)
    (at 79.1 101.9 90)
    (descr "Capacitor SMD 0805")
    (tags "capacitor SMD 0805")
    (property "Author" "Antmicro")
    (property "Dielectric" "")
    (property "License" "Apache-2.0")
    (property "MPN" "C0805C476M9PACTU")
    (property "Manufacturer" "KEMET")
    (property "Sheetfile" "poe.kicad_sch")
    (property "Sheetname" "PoE")
    (property "Val" "47u")
    (property "Voltage" "")
    (attr smd)
    (fp_text reference "C149" (at 4.48 0.35 270) (layer "B.SilkS")
      (effects (font (size 0.7 0.7) (thickness 0.15)) (justify left bottom mirror))
    )
    (fp_text value "C_47u_0805" (at 0 -1.947 270) (layer "B.Fab")
      (effects (font (size 0.7 0.7) (thickness 0.15)) (justify left bottom mirror))
    )
    (fp_text user "Author: Antmicro" (at -1.9 -5.947 270) (layer "B.Fab") hide
      (effects (font (size 0.7 0.7) (thickness 0.15)) (justify left bottom mirror))
    )
    (fp_text user "${REFERENCE}" (at -1.9 -3.947 270) (layer "B.Fab") hide
      (effects (font (size 0.7 0.7) (thickness 0.15)) (justify left bottom mirror))
    )
    (fp_text user "License: Apache-2.0" (at -1.9 -4.947 270) (layer "B.Fab") hide
      (effects (font (size 0.7 0.7) (thickness 0.15)) (justify left bottom mirror))
    )
    (fp_line (start -0.3 -0.8) (end 0.3 -0.8) (layer "B.SilkS") (width 0.15))
    (fp_line (start -0.3 0.8) (end 0.3 0.8) (layer "B.SilkS") (width 0.15))
    (fp_rect (start -1.9 0.93) (end 1.9 -0.93) (layer "B.CrtYd") (width 0.05) (fill none))
    (fp_rect (start -0.95 0.675) (end 0.95 -0.675) (layer "B.Fab") (width 0.15) (fill none))
    (pad "1" smd rect (at -1.05 0 90) (size 1.2 1.2) (layers "B.Cu" "B.Paste" "B.Mask")
      (net 136 "5V_POE") (pintype "passive"))
    (pad "2" smd rect (at 1.05 0 90) (size 1.2 1.2) (layers "B.Cu" "B.Paste" "B.Mask")
      (net 1 "GND") (pintype "passive"))
  )
	(footprint "sa800u-baseboard-hw-footprints:C_0402_1005Metric" (layer "B.Cu")
    (tedit 616D63CF)
    (at 73.8 102.2 90)
    (descr "Capacitor SMD 0402")
    (tags "capacitor SMD 0402")
    (property "Author" "Antmicro")
    (property "Dielectric" "X5R")
    (property "License" "Apache-2.0")
    (property "MPN" "GRM155R61H104KE14D")
    (property "Manufacturer" "Murata")
    (property "Sheetfile" "poe.kicad_sch")
    (property "Sheetname" "PoE")
    (property "Val" "100n")
    (property "Voltage" "50V")
    (attr smd)
    (fp_text reference "C151" (at 1.46 -1.67 270) (layer "B.SilkS")
      (effects (font (size 0.7 0.7) (thickness 0.15)) (justify left bottom mirror))
    )
    (fp_text value "C_100n_0402" (at 0 -1.4 270) (layer "B.Fab")
      (effects (font (size 0.7 0.7) (thickness 0.15)) (justify left bottom mirror))
    )
    (fp_text user "License: Apache-2.0" (at -0.932 -5.17 270) (layer "B.Fab") hide
      (effects (font (size 0.7 0.7) (thickness 0.15)) (justify left bottom mirror))
    )
    (fp_text user "Author: Antmicro" (at -0.932 -4.17 270) (layer "B.Fab") hide
      (effects (font (size 0.7 0.7) (thickness 0.15)) (justify left bottom mirror))
    )
    (fp_text user "${REFERENCE}" (at -0.932 -3.168 270) (layer "B.Fab") hide
      (effects (font (size 0.7 0.7) (thickness 0.15)) (justify left bottom mirror))
    )
    (fp_rect (start -0.94 0.47) (end 0.94 -0.47) (layer "B.CrtYd") (width 0.05) (fill none))
    (fp_rect (start -0.499 0.249) (end 0.499 -0.249) (layer "B.Fab") (width 0.15) (fill none))
    (pad "1" smd roundrect (at -0.484 0 90) (size 0.59 0.64) (layers "B.Cu" "B.Paste" "B.Mask") (roundrect_rratio 0.25)
      (net 136 "5V_POE") (pintype "passive"))
    (pad "2" smd roundrect (at 0.484 0 90) (size 0.59 0.64) (layers "B.Cu" "B.Paste" "B.Mask") (roundrect_rratio 0.25)
      (net 1 "GND") (pintype "passive"))
  )
	(footprint "sa800u-baseboard-hw-footprints:SOIC-4_4.2x5.0mm_P5.7mm" (layer "B.Cu")
    (tedit 6215E1D7)
    (at 58.1 125.6 -90)
    (property "Author" "Antmicro")
    (property "License" "Apache-2.0")
    (property "MPN" "MB10S")
    (property "Manufacturer" "Multicomp")
    (property "Sheetfile" "poe.kicad_sch")
    (property "Sheetname" "PoE")
    (attr smd)
    (fp_text reference "D29" (at 4.72 -0.98 180) (layer "B.SilkS")
      (effects (font (size 0.7 0.7) (thickness 0.15)) (justify left bottom mirror))
    )
    (fp_text value "MB10S" (at 0 -3.6 90) (layer "B.Fab")
      (effects (font (size 0.7 0.7) (thickness 0.15)) (justify left bottom mirror))
    )
    (fp_text user "${REFERENCE}" (at -4.111 -5.347 90) (layer "B.Fab") hide
      (effects (font (size 0.7 0.7) (thickness 0.15)) (justify left bottom mirror))
    )
    (fp_text user "Author: Antmicro" (at -4.111 -6.546 90) (layer "B.Fab") hide
      (effects (font (size 0.7 0.7) (thickness 0.15)) (justify left bottom mirror))
    )
    (fp_text user "License: Apache-2.0" (at -4.111 -7.746 90) (layer "B.Fab") hide
      (effects (font (size 0.7 0.7) (thickness 0.15)) (justify left bottom mirror))
    )
    (fp_line (start -2.1 2.5) (end 2.101 2.5) (layer "B.SilkS") (width 0.15))
    (fp_line (start -2.101 -2.479) (end 2.1 -2.479) (layer "B.SilkS") (width 0.15))
    (fp_circle (center -2.55 2) (end -2.451 2) (layer "B.SilkS") (width 0.15) (fill solid))
    (fp_rect (start -3.8 2.7) (end 3.8 -2.7) (layer "B.CrtYd") (width 0.05) (fill none))
    (fp_line (start -2.101 -2.479) (end -2.101 2.48) (layer "B.Fab") (width 0.15))
    (fp_line (start -2.101 2.48) (end 2.1 2.48) (layer "B.Fab") (width 0.15))
    (fp_line (start 2.1 2.48) (end 2.1 -2.479) (layer "B.Fab") (width 0.15))
    (fp_line (start 2.1 -2.479) (end -2.101 -2.479) (layer "B.Fab") (width 0.15))
    (pad "1" smd roundrect (at -2.851 1.226 270) (size 1.8 1) (layers "B.Cu" "B.Paste" "B.Mask") (roundrect_rratio 0.25)
      (net 175 "Net-(D29-Pad1)") (pinfunction "1") (pintype "passive"))
    (pad "2" smd roundrect (at -2.851 -1.225 270) (size 1.8 1) (layers "B.Cu" "B.Paste" "B.Mask") (roundrect_rratio 0.25)
      (net 379 "Net-(D29-Pad2)") (pinfunction "2") (pintype "passive"))
    (pad "3" smd roundrect (at 2.85 -1.225 270) (size 1.8 1) (layers "B.Cu" "B.Paste" "B.Mask") (roundrect_rratio 0.25)
      (net 5 "PAIR36") (pinfunction "3") (pintype "passive"))
    (pad "4" smd roundrect (at 2.85 1.226 270) (size 1.8 1) (layers "B.Cu" "B.Paste" "B.Mask") (roundrect_rratio 0.25)
      (net 6 "PAIR12") (pinfunction "4") (pintype "passive"))
  )
	(footprint "sa800u-baseboard-hw-footprints:SOIC-4_4.2x5.0mm_P5.7mm" (layer "B.Cu")
    (tedit 6215E1D7)
    (at 63.7 125.6 -90)
    (property "Author" "Antmicro")
    (property "License" "Apache-2.0")
    (property "MPN" "MB10S")
    (property "Manufacturer" "Multicomp")
    (property "Sheetfile" "poe.kicad_sch")
    (property "Sheetname" "PoE")
    (attr smd)
    (fp_text reference "D30" (at 4.72 -0.76 180) (layer "B.SilkS")
      (effects (font (size 0.7 0.7) (thickness 0.15)) (justify left bottom mirror))
    )
    (fp_text value "MB10S" (at 0 -3.6 90) (layer "B.Fab")
      (effects (font (size 0.7 0.7) (thickness 0.15)) (justify left bottom mirror))
    )
    (fp_text user "${REFERENCE}" (at -4.111 -5.347 90) (layer "B.Fab") hide
      (effects (font (size 0.7 0.7) (thickness 0.15)) (justify left bottom mirror))
    )
    (fp_text user "Author: Antmicro" (at -4.111 -6.546 90) (layer "B.Fab") hide
      (effects (font (size 0.7 0.7) (thickness 0.15)) (justify left bottom mirror))
    )
    (fp_text user "License: Apache-2.0" (at -4.111 -7.746 90) (layer "B.Fab") hide
      (effects (font (size 0.7 0.7) (thickness 0.15)) (justify left bottom mirror))
    )
    (fp_line (start -2.101 -2.479) (end 2.1 -2.479) (layer "B.SilkS") (width 0.15))
    (fp_line (start -2.1 2.5) (end 2.101 2.5) (layer "B.SilkS") (width 0.15))
    (fp_circle (center -2.55 2) (end -2.451 2) (layer "B.SilkS") (width 0.15) (fill solid))
    (fp_rect (start -3.8 2.7) (end 3.8 -2.7) (layer "B.CrtYd") (width 0.05) (fill none))
    (fp_line (start -2.101 2.48) (end 2.1 2.48) (layer "B.Fab") (width 0.15))
    (fp_line (start 2.1 2.48) (end 2.1 -2.479) (layer "B.Fab") (width 0.15))
    (fp_line (start 2.1 -2.479) (end -2.101 -2.479) (layer "B.Fab") (width 0.15))
    (fp_line (start -2.101 -2.479) (end -2.101 2.48) (layer "B.Fab") (width 0.15))
    (pad "1" smd roundrect (at -2.851 1.226 270) (size 1.8 1) (layers "B.Cu" "B.Paste" "B.Mask") (roundrect_rratio 0.25)
      (net 175 "Net-(D29-Pad1)") (pinfunction "1") (pintype "passive"))
    (pad "2" smd roundrect (at -2.851 -1.225 270) (size 1.8 1) (layers "B.Cu" "B.Paste" "B.Mask") (roundrect_rratio 0.25)
      (net 379 "Net-(D29-Pad2)") (pinfunction "2") (pintype "passive"))
    (pad "3" smd roundrect (at 2.85 -1.225 270) (size 1.8 1) (layers "B.Cu" "B.Paste" "B.Mask") (roundrect_rratio 0.25)
      (net 2 "PAIR78") (pinfunction "3") (pintype "passive"))
    (pad "4" smd roundrect (at 2.85 1.226 270) (size 1.8 1) (layers "B.Cu" "B.Paste" "B.Mask") (roundrect_rratio 0.25)
      (net 3 "PAIR45") (pinfunction "4") (pintype "passive"))
  )
	(footprint "sa800u-baseboard-hw-footprints:DO-214AC" (layer "B.Cu")
    (tedit 626A9B82)
    (at 61 115.9 180)
    (property "Author" "Antmicro")
    (property "License" "Apache-2.0")
    (property "MPN" "SMAJ58A-13-F")
    (property "Manufacturer" "Diodes Incorporated")
    (property "Sheetfile" "poe.kicad_sch")
    (property "Sheetname" "PoE")
    (attr smd)
    (fp_text reference "D31" (at 3.38 1.05 90) (layer "B.SilkS")
      (effects (font (size 0.7 0.7) (thickness 0.15)) (justify left bottom mirror))
    )
    (fp_text value "SMAJ58A-13-F" (at 0 -2.45) (layer "B.Fab")
      (effects (font (size 0.7 0.7) (thickness 0.15)) (justify left bottom mirror))
    )
    (fp_text user "Author: Antmicro" (at -3.301 -5.65) (layer "B.Fab") hide
      (effects (font (size 0.7 0.7) (thickness 0.15)) (justify left bottom mirror))
    )
    (fp_text user "${REFERENCE}" (at -3.301 -4.45) (layer "B.Fab") hide
      (effects (font (size 0.7 0.7) (thickness 0.15)) (justify left bottom mirror))
    )
    (fp_text user "License: Apache-2.0" (at -3.301 -6.85) (layer "B.Fab") hide
      (effects (font (size 0.7 0.7) (thickness 0.15)) (justify left bottom mirror))
    )
    (fp_line (start -0.9 -1.3) (end -0.9 1.3) (layer "B.SilkS") (width 0.15))
    (fp_rect (start -3.25 1.55) (end 3.25 -1.55) (layer "B.CrtYd") (width 0.05) (fill none))
    (fp_line (start -2.15 1.301) (end -2.15 -1.3) (layer "B.Fab") (width 0.15))
    (fp_line (start -1.363 1.301) (end -1.442 1.301) (layer "B.Fab") (width 0.15))
    (fp_line (start -2.15 1.301) (end 2.148 1.301) (layer "B.Fab") (width 0.15))
    (fp_line (start -1.442 -1.3) (end -1.365 -1.3) (layer "B.Fab") (width 0.15))
    (fp_line (start 2.148 1.301) (end 2.148 -1.3) (layer "B.Fab") (width 0.15))
    (fp_line (start -2.15 -1.3) (end 2.148 -1.3) (layer "B.Fab") (width 0.15))
    (fp_rect (start -1.363 1.301) (end -1.1 -1.3) (layer "B.Fab") (width 0.15) (fill solid))
    (pad "A" smd roundrect (at 1.999 0 180) (size 2 2.1) (layers "B.Cu" "B.Paste" "B.Mask") (roundrect_rratio 0.1)
      (net 135 "/PoE/VSS_POE") (pinfunction "A") (pintype "passive"))
    (pad "K" smd roundrect (at -2 0 180) (size 2 2.1) (layers "B.Cu" "B.Paste" "B.Mask") (roundrect_rratio 0.1)
      (net 73 "/PoE/VDD_POE") (pinfunction "K") (pintype "passive"))
  )
	(footprint "sa800u-baseboard-hw-footprints:FB_0805_2012Metric" (layer "B.Cu")
    (tedit 5D5D3F54)
    (at 64 119.5 90)
    (property "Author" "Antmicro")
    (property "License" "Apache-2.0")
    (property "MPN" "BLM21PG221SN1D")
    (property "Manufacturer" "Murata")
    (property "Sheetfile" "poe.kicad_sch")
    (property "Sheetname" "PoE")
    (attr smd)
    (fp_text reference "FB4" (at 0.96 1.71 270) (layer "B.SilkS")
      (effects (font (size 0.7 0.7) (thickness 0.15)) (justify left bottom mirror))
    )
    (fp_text value "FB_220Z_2A_0805" (at 0 -1.8 270) (layer "B.Fab")
      (effects (font (size 0.7 0.7) (thickness 0.15)) (justify left bottom mirror))
    )
    (fp_text user "License: Apache-2.0" (at -1.9 -5.75 270) (layer "B.Fab") hide
      (effects (font (size 0.7 0.7) (thickness 0.15)) (justify left bottom mirror))
    )
    (fp_text user "${REFERENCE}" (at -1.9 -3.1 270) (layer "B.Fab") hide
      (effects (font (size 0.7 0.7) (thickness 0.15)) (justify left bottom mirror))
    )
    (fp_text user "Author: Antmicro" (at -1.9 -4.4 270) (layer "B.Fab") hide
      (effects (font (size 0.7 0.7) (thickness 0.15)) (justify left bottom mirror))
    )
    (fp_line (start -0.3 0.701) (end 0.298 0.701) (layer "B.SilkS") (width 0.15))
    (fp_line (start -0.32 -0.699) (end 0.28 -0.699) (layer "B.SilkS") (width 0.15))
    (fp_rect (start -1.75 0.85) (end 1.75 -0.85) (layer "B.CrtYd") (width 0.05) (fill none))
    (fp_line (start -0.951 0.682) (end 0.949 0.682) (layer "B.Fab") (width 0.15))
    (fp_line (start -0.951 0.677) (end -0.951 -0.675) (layer "B.Fab") (width 0.15))
    (fp_line (start 0.949 0.677) (end 0.949 -0.675) (layer "B.Fab") (width 0.15))
    (fp_line (start -0.951 -0.68) (end 0.949 -0.68) (layer "B.Fab") (width 0.15))
    (pad "1" smd roundrect (at -1.1 0.001 90) (size 1 1.4) (layers "B.Cu" "B.Paste" "B.Mask") (roundrect_rratio 0.15)
      (net 175 "Net-(D29-Pad1)") (pintype "passive"))
    (pad "2" smd roundrect (at 1.1 0.001 90) (size 1 1.4) (layers "B.Cu" "B.Paste" "B.Mask") (roundrect_rratio 0.15)
      (net 73 "/PoE/VDD_POE") (pintype "passive"))
  )
)
